(kicad_pcb
	(version 20260206)
	(generator "pcbnew")
	(generator_version "10.0")
	(general
		(thickness 1.6)
		(legacy_teardrops no)
	)
	(paper "A4")
	(title_block
		(title "Wiwynn_Tioga_Pass_MB.brd")
		(comment 1 "Tioga Pass / footprints 4233-4239 of 4770")
	)
	(layers
		(0 "F.Cu" signal "TOP")
		(4 "In1.Cu" signal "L2GND")
		(6 "In2.Cu" signal "L3")
		(8 "In3.Cu" signal "L4GND")
		(10 "In4.Cu" signal "L5")
		(12 "In5.Cu" signal "L6GND")
		(14 "In6.Cu" signal "L7VCC")
		(16 "In7.Cu" signal "L8VCC")
		(18 "In8.Cu" signal "L9GND")
		(20 "In9.Cu" signal "L10")
		(22 "In10.Cu" signal "L11GND")
		(24 "In11.Cu" signal "L12")
		(26 "In12.Cu" signal "L13GND")
		(2 "B.Cu" signal "BOTTOM")
		(9 "F.Adhes" user "F.Adhesive")
		(11 "B.Adhes" user "B.Adhesive")
		(13 "F.Paste" user "Package Geometry/Pastemask Top")
		(15 "B.Paste" user "Package Geometry/Pastemask Bottom")
		(5 "F.SilkS" user "Ref Des/Silkscreen Top")
		(7 "B.SilkS" user "Ref Des/Silkscreen Bottom")
		(1 "F.Mask" user "Board Geometry/Soldermask Top")
		(3 "B.Mask" user "Board Geometry/Soldermask Bottom")
		(17 "Dwgs.User" user "User.Drawings")
		(19 "Cmts.User" user "User.Comments")
		(21 "Eco1.User" user "User.Eco1")
		(23 "Eco2.User" user "User.Eco2")
		(25 "Edge.Cuts" user "Board Geometry/Outline")
		(27 "Margin" user)
		(31 "F.CrtYd" user "Package Geometry/Place Bound Top")
		(29 "B.CrtYd" user "Package Geometry/Place Bound Bottom")
		(35 "F.Fab" user "Ref Des/Assembly Top")
		(33 "B.Fab" user "Ref Des/Assembly Bottom")
	)
	(footprint ""
		(layer "B.Cu")
		(at 435.434994 -42.0116 -90)
		(property "Reference" "C25W5"
			(at 0.8382 -0.67818 270)
			(unlocked yes)
			(layer "B.SilkS")
			(effects
				(font
					(size 0.4064 0.254)
					(thickness 0.1524)
				)
				(justify left mirror)
			)
		)
		(property "Value" ""
			(at 0 0 90)
			(layer "B.Fab")
			(effects
				(font
					(size 1.27 1.27)
				)
				(justify mirror)
			)
		)
		(duplicate_pad_numbers_are_jumpers no)
		(fp_poly
			(pts
				(xy -0.3048 -0.1016) (xy -0.3048 0.9906) (xy 0.3048 0.9906) (xy 0.3048 -0.1016)
			)
			(stroke
				(width 0)
				(type default)
			)
			(fill no)
			(layer "B.CrtYd")
		)
		(fp_line
			(start -0.3048 0.9906)
			(end -0.3048 -0.1016)
			(stroke
				(width 0.1)
				(type default)
			)
			(layer "B.Fab")
		)
		(fp_line
			(start 0.3048 0.9906)
			(end -0.3048 0.9906)
			(stroke
				(width 0.1)
				(type default)
			)
			(layer "B.Fab")
		)
		(fp_line
			(start -0.3048 -0.1016)
			(end 0.3048 -0.1016)
			(stroke
				(width 0.1)
				(type default)
			)
			(layer "B.Fab")
		)
		(fp_line
			(start 0.3048 -0.1016)
			(end 0.3048 0.9906)
			(stroke
				(width 0.1)
				(type default)
			)
			(layer "B.Fab")
		)
		(pad "1" smd rect
			(at 0 0 90)
			(size 0.508 0.508)
			(layers "B.Cu" "B.Mask" "B.Paste")
			(net "P1V2_AUX_BMC")
		)
		(pad "2" smd rect
			(at 0 0.889 90)
			(size 0.508 0.508)
			(layers "B.Cu" "B.Mask" "B.Paste")
			(net "GND")
		)
		(zone
			(layer "B.Cu")
			(hatch none 0.5)
			(connect_pads
				(clearance 0)
			)
			(min_thickness 0.25)
			(keepout
				(tracks not_allowed)
				(vias allowed)
				(pads allowed)
				(copperpour not_allowed)
				(footprints allowed)
			)
			(placement
				(enabled no)
				(sheetname "")
			)
			(fill
				(thermal_gap 0.5)
				(thermal_bridge_width 0.5)
				(island_removal_mode 0)
			)
			(polygon
				(pts
					(xy 434.799994 -41.7576) (xy 434.799994 -42.2656) (xy 435.180994 -42.2656) (xy 435.180994 -41.7576)
				)
			)
		)
		(zone
			(layer "B.Cu")
			(hatch none 0.5)
			(connect_pads
				(clearance 0)
			)
			(min_thickness 0.25)
			(keepout
				(tracks allowed)
				(vias not_allowed)
				(pads allowed)
				(copperpour not_allowed)
				(footprints allowed)
			)
			(placement
				(enabled no)
				(sheetname "")
			)
			(fill
				(thermal_gap 0.5)
				(thermal_bridge_width 0.5)
				(island_removal_mode 0)
			)
			(polygon
				(pts
					(xy 435.180994 -41.7576) (xy 435.180994 -42.2656) (xy 434.799994 -42.2656) (xy 434.799994 -41.7576)
				)
			)
		)
	)
	(footprint ""
		(layer "B.Cu")
		(at 13.921232 3.752342 90)
		(property "Reference" "R9U8"
			(at 0 0 90)
			(layer "B.SilkS")
			(hide yes)
			(effects
				(font
					(size 1.27 1.27)
				)
				(justify mirror)
			)
		)
		(property "Value" ""
			(at 0 0 90)
			(layer "B.Fab")
			(effects
				(font
					(size 1.27 1.27)
				)
				(justify mirror)
			)
		)
		(duplicate_pad_numbers_are_jumpers no)
		(fp_poly
			(pts
				(xy 0.2794 -0.1016) (xy -0.2794 -0.1016) (xy -0.2794 0.9906) (xy 0.2794 0.9906)
			)
			(stroke
				(width 0)
				(type default)
			)
			(fill no)
			(layer "B.CrtYd")
		)
		(fp_line
			(start 0.2794 -0.1016)
			(end 0.2794 0.9906)
			(stroke
				(width 0.1)
				(type default)
			)
			(layer "B.Fab")
		)
		(fp_line
			(start -0.2794 -0.1016)
			(end 0.2794 -0.1016)
			(stroke
				(width 0.1)
				(type default)
			)
			(layer "B.Fab")
		)
		(fp_line
			(start 0.2794 0.9906)
			(end -0.2794 0.9906)
			(stroke
				(width 0.1)
				(type default)
			)
			(layer "B.Fab")
		)
		(fp_line
			(start -0.2794 0.9906)
			(end -0.2794 -0.1016)
			(stroke
				(width 0.1)
				(type default)
			)
			(layer "B.Fab")
		)
		(pad "1" smd rect
			(at 0 0 270)
			(size 0.508 0.508)
			(layers "B.Cu" "B.Mask" "B.Paste")
			(net "P3V3_STBY")
		)
		(pad "2" smd rect
			(at 0 0.889 270)
			(size 0.508 0.508)
			(layers "B.Cu" "B.Mask" "B.Paste")
			(net "VR_PVDDQ_GHJ_VREN")
		)
		(zone
			(layer "B.Cu")
			(hatch none 0.5)
			(connect_pads
				(clearance 0)
			)
			(min_thickness 0.25)
			(keepout
				(tracks allowed)
				(vias not_allowed)
				(pads allowed)
				(copperpour not_allowed)
				(footprints allowed)
			)
			(placement
				(enabled no)
				(sheetname "")
			)
			(fill
				(thermal_gap 0.5)
				(thermal_bridge_width 0.5)
				(island_removal_mode 0)
			)
			(polygon
				(pts
					(xy 14.175232 3.498342) (xy 14.175232 4.006342) (xy 14.556232 4.006342) (xy 14.556232 3.498342)
				)
			)
		)
		(zone
			(layer "B.Cu")
			(hatch none 0.5)
			(connect_pads
				(clearance 0)
			)
			(min_thickness 0.25)
			(keepout
				(tracks not_allowed)
				(vias allowed)
				(pads allowed)
				(copperpour not_allowed)
				(footprints allowed)
			)
			(placement
				(enabled no)
				(sheetname "")
			)
			(fill
				(thermal_gap 0.5)
				(thermal_bridge_width 0.5)
				(island_removal_mode 0)
			)
			(polygon
				(pts
					(xy 14.556232 3.498342) (xy 14.556232 4.006342) (xy 14.175232 4.006342) (xy 14.175232 3.498342)
				)
			)
		)
	)
	(footprint ""
		(layer "B.Cu")
		(at 164.084 -67.31)
		(property "Reference" "R6P39"
			(at 0 0 0)
			(layer "B.SilkS")
			(hide yes)
			(effects
				(font
					(size 1.27 1.27)
				)
				(justify mirror)
			)
		)
		(property "Value" ""
			(at 0 0 0)
			(layer "B.Fab")
			(effects
				(font
					(size 1.27 1.27)
				)
				(justify mirror)
			)
		)
		(duplicate_pad_numbers_are_jumpers no)
		(fp_poly
			(pts
				(xy 0.2794 -0.1016) (xy -0.2794 -0.1016) (xy -0.2794 0.9906) (xy 0.2794 0.9906)
			)
			(stroke
				(width 0)
				(type default)
			)
			(fill no)
			(layer "B.CrtYd")
		)
		(fp_line
			(start -0.2794 -0.1016)
			(end 0.2794 -0.1016)
			(stroke
				(width 0.1)
				(type default)
			)
			(layer "B.Fab")
		)
		(fp_line
			(start -0.2794 0.9906)
			(end -0.2794 -0.1016)
			(stroke
				(width 0.1)
				(type default)
			)
			(layer "B.Fab")
		)
		(fp_line
			(start 0.2794 -0.1016)
			(end 0.2794 0.9906)
			(stroke
				(width 0.1)
				(type default)
			)
			(layer "B.Fab")
		)
		(fp_line
			(start 0.2794 0.9906)
			(end -0.2794 0.9906)
			(stroke
				(width 0.1)
				(type default)
			)
			(layer "B.Fab")
		)
		(pad "1" smd rect
			(at 0 0 180)
			(size 0.508 0.508)
			(layers "B.Cu" "B.Mask" "B.Paste")
			(net "P3V3_STBY")
		)
		(pad "2" smd rect
			(at 0 0.889 180)
			(size 0.508 0.508)
			(layers "B.Cu" "B.Mask" "B.Paste")
			(net "FM_CPU1_SKTOCC_LVT3_N")
		)
		(zone
			(layer "B.Cu")
			(hatch none 0.5)
			(connect_pads
				(clearance 0)
			)
			(min_thickness 0.25)
			(keepout
				(tracks allowed)
				(vias not_allowed)
				(pads allowed)
				(copperpour not_allowed)
				(footprints allowed)
			)
			(placement
				(enabled no)
				(sheetname "")
			)
			(fill
				(thermal_gap 0.5)
				(thermal_bridge_width 0.5)
				(island_removal_mode 0)
			)
			(polygon
				(pts
					(xy 164.338 -67.056) (xy 163.83 -67.056) (xy 163.83 -66.675) (xy 164.338 -66.675)
				)
			)
		)
		(zone
			(layer "B.Cu")
			(hatch none 0.5)
			(connect_pads
				(clearance 0)
			)
			(min_thickness 0.25)
			(keepout
				(tracks not_allowed)
				(vias allowed)
				(pads allowed)
				(copperpour not_allowed)
				(footprints allowed)
			)
			(placement
				(enabled no)
				(sheetname "")
			)
			(fill
				(thermal_gap 0.5)
				(thermal_bridge_width 0.5)
				(island_removal_mode 0)
			)
			(polygon
				(pts
					(xy 164.338 -66.675) (xy 163.83 -66.675) (xy 163.83 -67.056) (xy 164.338 -67.056)
				)
			)
		)
	)
	(footprint ""
		(layer "B.Cu")
		(at 61.285628 -165.04158 -90)
		(property "Reference" "T1D3"
			(at 0 0 90)
			(layer "B.SilkS")
			(hide yes)
			(effects
				(font
					(size 1.27 1.27)
				)
				(justify mirror)
			)
		)
		(property "Value" "*"
			(at 3.4036 -4.46405 270)
			(unlocked yes)
			(layer "B.Fab")
			(hide yes)
			(effects
				(font
					(size 0.889 0.889)
					(thickness 0.1524)
				)
				(justify mirror)
			)
		)
		(property "Device Type" "TEST-PAD-12P-1-GP-U_DISCRET-GBA"
			(at 3.4036 -5.98805 270)
			(unlocked yes)
			(layer "B.Fab")
			(hide yes)
			(effects
				(font
					(size 0.889 0.889)
					(thickness 0.1524)
				)
				(justify mirror)
			)
		)
		(duplicate_pad_numbers_are_jumpers no)
		(fp_line
			(start -2.3622 3.4798)
			(end 2.3876 3.4798)
			(stroke
				(width 0.1524)
				(type default)
			)
			(layer "B.SilkS")
		)
		(fp_line
			(start 2.3876 3.4798)
			(end 2.3876 -4.826)
			(stroke
				(width 0.1524)
				(type default)
			)
			(layer "B.SilkS")
		)
		(fp_line
			(start -2.3622 -4.826)
			(end -2.3622 3.4798)
			(stroke
				(width 0.1524)
				(type default)
			)
			(layer "B.SilkS")
		)
		(fp_line
			(start 2.3876 -4.826)
			(end -2.3622 -4.826)
			(stroke
				(width 0.1524)
				(type default)
			)
			(layer "B.SilkS")
		)
		(fp_rect
			(start 2.6416 3.7338)
			(end -2.6162 -5.08)
			(stroke
				(width 0)
				(type default)
			)
			(fill no)
			(layer "B.CrtYd")
		)
		(fp_rect
			(start 2.6416 3.7338)
			(end -2.6162 -5.08)
			(stroke
				(width 0)
				(type default)
			)
			(fill no)
			(layer "B.Fab")
		)
		(pad "1" smd circle
			(at -0.496824 -1.301496 90)
			(size 0.6604 0.6604)
			(layers "B.Cu" "B.Mask" "B.Paste")
			(net "L3_85OHM_5INCH_DP")
		)
		(pad "2" smd circle
			(at 0.503936 -1.301496 90)
			(size 0.6604 0.6604)
			(layers "B.Cu" "B.Mask" "B.Paste")
			(net "L3_85OHM_5INCH_DN")
		)
		(pad "3" smd custom
			(at 0.00889 0.370078 90)
			(size 0.74295 0.74295)
			(layers "B.Cu" "B.Mask" "B.Paste")
			(net "GND")
			(options
				(clearance outline)
				(anchor circle)
			)
			(primitives
				(gr_poly
					(pts
						(xy -2.1209 -1.4859) (xy 2.1209 -1.4859) (xy 2.1209 1.4859) (xy 1.08585 1.4859) (xy 1.08585 0.4699)
						(xy -1.08585 0.4699) (xy -1.08585 1.4859) (xy -2.1209 1.4859)
					)
					(width 0)
					(fill yes)
				)
			)
		)
		(pad "4" thru_hole circle
			(at -1.266444 -3.851656 90)
			(size 1.4478 1.4478)
			(drill 1.0414)
			(layers "*.Cu" "*.Mask")
			(remove_unused_layers no)
			(net "GND")
			(clearance 0.1524)
			(thermal_gap 0.1524)
		)
		(pad "5" thru_hole circle
			(at 1.273556 -3.851656 90)
			(size 1.4478 1.4478)
			(drill 1.0414)
			(layers "*.Cu" "*.Mask")
			(remove_unused_layers no)
			(net "GND")
			(clearance 0.1524)
			(thermal_gap 0.1524)
		)
		(pad "6" thru_hole circle
			(at -1.266444 2.498344 90)
			(size 1.4478 1.4478)
			(drill 1.0414)
			(layers "*.Cu" "*.Mask")
			(remove_unused_layers no)
			(net "GND")
			(clearance 0.1524)
			(thermal_gap 0.1524)
		)
		(pad "7" thru_hole circle
			(at 1.273556 2.498344 90)
			(size 1.4478 1.4478)
			(drill 1.0414)
			(layers "*.Cu" "*.Mask")
			(remove_unused_layers no)
			(net "GND")
			(clearance 0.1524)
			(thermal_gap 0.1524)
		)
		(pad "8" thru_hole circle
			(at -1.27 -0.4572 90)
			(size 0.7112 0.7112)
			(drill 0.4064)
			(layers "*.Cu" "*.Mask")
			(remove_unused_layers no)
			(net "GND")
			(clearance 0.1016)
			(thermal_gap 0.1016)
		)
		(pad "9" thru_hole circle
			(at -1.27 0.762 90)
			(size 0.7112 0.7112)
			(drill 0.4064)
			(layers "*.Cu" "*.Mask")
			(remove_unused_layers no)
			(net "GND")
			(clearance 0.1016)
			(thermal_gap 0.1016)
		)
		(pad "10" thru_hole circle
			(at 0.0254 0.762 90)
			(size 0.7112 0.7112)
			(drill 0.4064)
			(layers "*.Cu" "*.Mask")
			(remove_unused_layers no)
			(net "GND")
			(clearance 0.1016)
			(thermal_gap 0.1016)
		)
		(pad "11" thru_hole circle
			(at 1.27 0.762 90)
			(size 0.7112 0.7112)
			(drill 0.4064)
			(layers "*.Cu" "*.Mask")
			(remove_unused_layers no)
			(net "GND")
			(clearance 0.1016)
			(thermal_gap 0.1016)
		)
		(pad "12" thru_hole circle
			(at 1.27 -0.4572 90)
			(size 0.7112 0.7112)
			(drill 0.4064)
			(layers "*.Cu" "*.Mask")
			(remove_unused_layers no)
			(net "GND")
			(clearance 0.1016)
			(thermal_gap 0.1016)
		)
	)
	(footprint ""
		(layer "B.Cu")
		(at 476.48876 -43.116246 -90)
		(property "Reference" "C9E6"
			(at 0 0 90)
			(layer "B.SilkS")
			(hide yes)
			(effects
				(font
					(size 1.27 1.27)
				)
				(justify mirror)
			)
		)
		(property "Value" "*"
			(at 0.0762 -6.2357 270)
			(unlocked yes)
			(layer "B.Fab")
			(hide yes)
			(effects
				(font
					(size 1.27 1.016)
					(thickness 0.1524)
				)
				(justify mirror)
			)
		)
		(property "Device Type" "SC22U16V5MX-4-GP_SMD-BCG5-SC22A"
			(at 0.0762 -8.2677 270)
			(unlocked yes)
			(layer "B.Fab")
			(hide yes)
			(effects
				(font
					(size 1.27 1.016)
					(thickness 0.1524)
				)
				(justify mirror)
			)
		)
		(duplicate_pad_numbers_are_jumpers no)
		(fp_line
			(start -0.635 0)
			(end 0.635 0)
			(stroke
				(width 0.508)
				(type default)
			)
			(layer "B.SilkS")
		)
		(fp_rect
			(start 0.9652 1.778)
			(end -0.9652 -1.778)
			(stroke
				(width 0)
				(type default)
			)
			(fill no)
			(layer "B.CrtYd")
		)
		(fp_poly
			(pts
				(xy 0.9652 -1.778) (xy -0.9652 -1.778) (xy -0.9652 1.778) (xy 0.9652 1.778)
			)
			(stroke
				(width 0)
				(type default)
			)
			(fill no)
			(layer "B.Fab")
		)
		(pad "1" smd rect
			(at 0 -0.9652 90)
			(size 1.397 1.143)
			(layers "B.Cu" "B.Mask" "B.Paste")
			(net "P1V5_LAN")
		)
		(pad "2" smd rect
			(at 0 0.9652 90)
			(size 1.397 1.143)
			(layers "B.Cu" "B.Mask" "B.Paste")
			(net "GND")
		)
	)
	(footprint ""
		(layer "B.Cu")
		(at 164.973 -55.245 90)
		(property "Reference" "C6R12"
			(at -3.20167 4.191 0)
			(unlocked yes)
			(layer "B.SilkS")
			(effects
				(font
					(size 0.7874 0.5842)
					(thickness 0.1524)
				)
				(justify mirror)
			)
		)
		(property "Value" ""
			(at 0 0 90)
			(layer "B.Fab")
			(effects
				(font
					(size 1.27 1.27)
				)
				(justify mirror)
			)
		)
		(duplicate_pad_numbers_are_jumpers no)
		(fp_line
			(start 2.563114 -1.616456)
			(end 2.563114 1.633728)
			(stroke
				(width 0.1524)
				(type default)
			)
			(layer "B.SilkS")
		)
		(fp_line
			(start 1.6002 -1.616456)
			(end 2.563114 -1.616456)
			(stroke
				(width 0.1524)
				(type default)
			)
			(layer "B.SilkS")
		)
		(fp_line
			(start -1.6002 -1.616456)
			(end -2.504948 -1.616456)
			(stroke
				(width 0.1524)
				(type default)
			)
			(layer "B.SilkS")
		)
		(fp_line
			(start -2.504948 -1.616456)
			(end -2.504948 1.633728)
			(stroke
				(width 0.1524)
				(type default)
			)
			(layer "B.SilkS")
		)
		(fp_line
			(start 2.563114 1.633728)
			(end 1.6002 1.633728)
			(stroke
				(width 0.1524)
				(type default)
			)
			(layer "B.SilkS")
		)
		(fp_line
			(start -2.504948 1.633728)
			(end -1.6002 1.633728)
			(stroke
				(width 0.1524)
				(type default)
			)
			(layer "B.SilkS")
		)
		(fp_line
			(start 2.286 7.366)
			(end 2.286 1.632712)
			(stroke
				(width 0.1524)
				(type default)
			)
			(layer "B.SilkS")
		)
		(fp_line
			(start 2.286 7.366)
			(end 1.60147 7.366)
			(stroke
				(width 0.1524)
				(type default)
			)
			(layer "B.SilkS")
		)
		(fp_line
			(start -2.286 7.366)
			(end -2.286 1.63195)
			(stroke
				(width 0.1524)
				(type default)
			)
			(layer "B.SilkS")
		)
		(fp_line
			(start -2.286 7.366)
			(end -1.600708 7.366)
			(stroke
				(width 0.1524)
				(type default)
			)
			(layer "B.SilkS")
		)
		(fp_rect
			(start 2.286 7.366)
			(end -2.286 -0.254)
			(stroke
				(width 0)
				(type default)
			)
			(fill no)
			(layer "B.CrtYd")
		)
		(fp_line
			(start 2.286 -0.254)
			(end -2.286 -0.254)
			(stroke
				(width 0.1)
				(type default)
			)
			(layer "B.Fab")
		)
		(fp_line
			(start -2.286 -0.254)
			(end -2.286 7.366)
			(stroke
				(width 0.1)
				(type default)
			)
			(layer "B.Fab")
		)
		(fp_line
			(start 2.286 7.366)
			(end 2.286 -0.254)
			(stroke
				(width 0.1)
				(type default)
			)
			(layer "B.Fab")
		)
		(fp_line
			(start -2.286 7.366)
			(end 2.286 7.366)
			(stroke
				(width 0.1)
				(type default)
			)
			(layer "B.Fab")
		)
		(pad "1" smd rect
			(at 0 0 270)
			(size 2.54 3.048)
			(layers "B.Cu" "B.Mask" "B.Paste")
			(net "PVCCIO_CPU1")
		)
		(pad "2" smd rect
			(at 0 7.112 270)
			(size 2.54 3.048)
			(layers "B.Cu" "B.Mask" "B.Paste")
			(net "GND")
		)
	)
	(footprint ""
		(layer "B.Cu")
		(at 293.87292 -67.16268)
		(property "Reference" "R4P19"
			(at 0 0 0)
			(layer "B.SilkS")
			(hide yes)
			(effects
				(font
					(size 1.27 1.27)
				)
				(justify mirror)
			)
		)
		(property "Value" ""
			(at 0 0 0)
			(layer "B.Fab")
			(effects
				(font
					(size 1.27 1.27)
				)
				(justify mirror)
			)
		)
		(duplicate_pad_numbers_are_jumpers no)
		(fp_poly
			(pts
				(xy 0.2794 -0.1016) (xy -0.2794 -0.1016) (xy -0.2794 0.9906) (xy 0.2794 0.9906)
			)
			(stroke
				(width 0)
				(type default)
			)
			(fill no)
			(layer "B.CrtYd")
		)
		(fp_line
			(start -0.2794 -0.1016)
			(end 0.2794 -0.1016)
			(stroke
				(width 0.1)
				(type default)
			)
			(layer "B.Fab")
		)
		(fp_line
			(start -0.2794 0.9906)
			(end -0.2794 -0.1016)
			(stroke
				(width 0.1)
				(type default)
			)
			(layer "B.Fab")
		)
		(fp_line
			(start 0.2794 -0.1016)
			(end 0.2794 0.9906)
			(stroke
				(width 0.1)
				(type default)
			)
			(layer "B.Fab")
		)
		(fp_line
			(start 0.2794 0.9906)
			(end -0.2794 0.9906)
			(stroke
				(width 0.1)
				(type default)
			)
			(layer "B.Fab")
		)
		(pad "1" smd rect
			(at 0 0 180)
			(size 0.508 0.508)
			(layers "B.Cu" "B.Mask" "B.Paste")
			(net "H_PMSYNC_CLK_24M_CPU0")
		)
		(pad "2" smd rect
			(at 0 0.889 180)
			(size 0.508 0.508)
			(layers "B.Cu" "B.Mask" "B.Paste")
			(net "H_PMSYNC_CLK_24M")
		)
		(zone
			(layer "B.Cu")
			(hatch none 0.5)
			(connect_pads
				(clearance 0)
			)
			(min_thickness 0.25)
			(keepout
				(tracks allowed)
				(vias not_allowed)
				(pads allowed)
				(copperpour not_allowed)
				(footprints allowed)
			)
			(placement
				(enabled no)
				(sheetname "")
			)
			(fill
				(thermal_gap 0.5)
				(thermal_bridge_width 0.5)
				(island_removal_mode 0)
			)
			(polygon
				(pts
					(xy 294.12692 -66.90868) (xy 293.61892 -66.90868) (xy 293.61892 -66.52768) (xy 294.12692 -66.52768)
				)
			)
		)
		(zone
			(layer "B.Cu")
			(hatch none 0.5)
			(connect_pads
				(clearance 0)
			)
			(min_thickness 0.25)
			(keepout
				(tracks not_allowed)
				(vias allowed)
				(pads allowed)
				(copperpour not_allowed)
				(footprints allowed)
			)
			(placement
				(enabled no)
				(sheetname "")
			)
			(fill
				(thermal_gap 0.5)
				(thermal_bridge_width 0.5)
				(island_removal_mode 0)
			)
			(polygon
				(pts
					(xy 294.12692 -66.52768) (xy 293.61892 -66.52768) (xy 293.61892 -66.90868) (xy 294.12692 -66.90868)
				)
			)
		)
	)
)
